(kicad_pcb
	(version 20260206)
	(generator "pcbnew")
	(generator_version "10.0")
	(general
		(thickness 1.6)
		(legacy_teardrops no)
	)
	(paper "A4")
	(title_block
		(title "Wiwynn_Tioga_Pass_MB.brd")
		(comment 1 "Tioga Pass / footprints 1367-1374 of 4770")
	)
	(layers
		(0 "F.Cu" signal "TOP")
		(4 "In1.Cu" signal "L2GND")
		(6 "In2.Cu" signal "L3")
		(8 "In3.Cu" signal "L4GND")
		(10 "In4.Cu" signal "L5")
		(12 "In5.Cu" signal "L6GND")
		(14 "In6.Cu" signal "L7VCC")
		(16 "In7.Cu" signal "L8VCC")
		(18 "In8.Cu" signal "L9GND")
		(20 "In9.Cu" signal "L10")
		(22 "In10.Cu" signal "L11GND")
		(24 "In11.Cu" signal "L12")
		(26 "In12.Cu" signal "L13GND")
		(2 "B.Cu" signal "BOTTOM")
		(9 "F.Adhes" user "F.Adhesive")
		(11 "B.Adhes" user "B.Adhesive")
		(13 "F.Paste" user "Package Geometry/Pastemask Top")
		(15 "B.Paste" user "Package Geometry/Pastemask Bottom")
		(5 "F.SilkS" user "Ref Des/Silkscreen Top")
		(7 "B.SilkS" user "Ref Des/Silkscreen Bottom")
		(1 "F.Mask" user "Board Geometry/Soldermask Top")
		(3 "B.Mask" user "Board Geometry/Soldermask Bottom")
		(17 "Dwgs.User" user "User.Drawings")
		(19 "Cmts.User" user "User.Comments")
		(21 "Eco1.User" user "User.Eco1")
		(23 "Eco2.User" user "User.Eco2")
		(25 "Edge.Cuts" user "Board Geometry/Outline")
		(27 "Margin" user)
		(31 "F.CrtYd" user "Package Geometry/Place Bound Top")
		(29 "B.CrtYd" user "Package Geometry/Place Bound Bottom")
		(35 "F.Fab" user "Ref Des/Assembly Top")
		(33 "B.Fab" user "Ref Des/Assembly Bottom")
	)
	(footprint ""
		(layer "F.Cu")
		(at 386.0165 -85.979 90)
		(property "Reference" "R7D13"
			(at 0 0 90)
			(layer "F.SilkS")
			(hide yes)
			(effects
				(font
					(size 1.27 1.27)
				)
			)
		)
		(property "Value" ""
			(at 0 0 90)
			(layer "F.Fab")
			(effects
				(font
					(size 1.27 1.27)
				)
			)
		)
		(duplicate_pad_numbers_are_jumpers no)
		(fp_poly
			(pts
				(xy -0.2794 -0.1016) (xy 0.2794 -0.1016) (xy 0.2794 0.9906) (xy -0.2794 0.9906)
			)
			(stroke
				(width 0)
				(type default)
			)
			(fill no)
			(layer "F.CrtYd")
		)
		(fp_line
			(start 0.2794 -0.1016)
			(end -0.2794 -0.1016)
			(stroke
				(width 0.1)
				(type default)
			)
			(layer "F.Fab")
		)
		(fp_line
			(start -0.2794 -0.1016)
			(end -0.2794 0.9906)
			(stroke
				(width 0.1)
				(type default)
			)
			(layer "F.Fab")
		)
		(fp_line
			(start 0.2794 0.9906)
			(end 0.2794 -0.1016)
			(stroke
				(width 0.1)
				(type default)
			)
			(layer "F.Fab")
		)
		(fp_line
			(start -0.2794 0.9906)
			(end 0.2794 0.9906)
			(stroke
				(width 0.1)
				(type default)
			)
			(layer "F.Fab")
		)
		(pad "1" smd rect
			(at 0 0 90)
			(size 0.508 0.508)
			(layers "F.Cu" "F.Mask" "F.Paste")
			(net "P3V3_STBY")
		)
		(pad "2" smd rect
			(at 0 0.889 90)
			(size 0.508 0.508)
			(layers "F.Cu" "F.Mask" "F.Paste")
			(net "RMII_BMC_PCH_SPRNGVLLE_RXER")
		)
		(zone
			(layer "F.Cu")
			(hatch none 0.5)
			(connect_pads
				(clearance 0)
			)
			(min_thickness 0.25)
			(keepout
				(tracks allowed)
				(vias not_allowed)
				(pads allowed)
				(copperpour not_allowed)
				(footprints allowed)
			)
			(placement
				(enabled no)
				(sheetname "")
			)
			(fill
				(thermal_gap 0.5)
				(thermal_bridge_width 0.5)
				(island_removal_mode 0)
			)
			(polygon
				(pts
					(xy 386.2705 -85.725) (xy 386.2705 -86.233) (xy 386.6515 -86.233) (xy 386.6515 -85.725)
				)
			)
		)
		(zone
			(layer "F.Cu")
			(hatch none 0.5)
			(connect_pads
				(clearance 0)
			)
			(min_thickness 0.25)
			(keepout
				(tracks not_allowed)
				(vias allowed)
				(pads allowed)
				(copperpour not_allowed)
				(footprints allowed)
			)
			(placement
				(enabled no)
				(sheetname "")
			)
			(fill
				(thermal_gap 0.5)
				(thermal_bridge_width 0.5)
				(island_removal_mode 0)
			)
			(polygon
				(pts
					(xy 386.6515 -85.725) (xy 386.6515 -86.233) (xy 386.2705 -86.233) (xy 386.2705 -85.725)
				)
			)
		)
	)
	(footprint ""
		(layer "F.Cu")
		(at 415.7345 -114.935 -90)
		(property "Reference" "R2M1"
			(at 0 0 270)
			(layer "F.SilkS")
			(hide yes)
			(effects
				(font
					(size 1.27 1.27)
				)
			)
		)
		(property "Value" ""
			(at 0 0 270)
			(layer "F.Fab")
			(effects
				(font
					(size 1.27 1.27)
				)
			)
		)
		(duplicate_pad_numbers_are_jumpers no)
		(fp_poly
			(pts
				(xy -0.2794 -0.1016) (xy 0.2794 -0.1016) (xy 0.2794 0.9906) (xy -0.2794 0.9906)
			)
			(stroke
				(width 0)
				(type default)
			)
			(fill no)
			(layer "F.CrtYd")
		)
		(fp_line
			(start -0.2794 0.9906)
			(end 0.2794 0.9906)
			(stroke
				(width 0.1)
				(type default)
			)
			(layer "F.Fab")
		)
		(fp_line
			(start 0.2794 0.9906)
			(end 0.2794 -0.1016)
			(stroke
				(width 0.1)
				(type default)
			)
			(layer "F.Fab")
		)
		(fp_line
			(start -0.2794 -0.1016)
			(end -0.2794 0.9906)
			(stroke
				(width 0.1)
				(type default)
			)
			(layer "F.Fab")
		)
		(fp_line
			(start 0.2794 -0.1016)
			(end -0.2794 -0.1016)
			(stroke
				(width 0.1)
				(type default)
			)
			(layer "F.Fab")
		)
		(pad "1" smd rect
			(at 0 0 270)
			(size 0.508 0.508)
			(layers "F.Cu" "F.Mask" "F.Paste")
			(net "FM_CPLD_ADR_TRIGGER_N")
		)
		(pad "2" smd rect
			(at 0 0.889 270)
			(size 0.508 0.508)
			(layers "F.Cu" "F.Mask" "F.Paste")
			(net "FM_CPLD_ADR_TRIGGER_R_N")
		)
		(zone
			(layer "F.Cu")
			(hatch none 0.5)
			(connect_pads
				(clearance 0)
			)
			(min_thickness 0.25)
			(keepout
				(tracks not_allowed)
				(vias allowed)
				(pads allowed)
				(copperpour not_allowed)
				(footprints allowed)
			)
			(placement
				(enabled no)
				(sheetname "")
			)
			(fill
				(thermal_gap 0.5)
				(thermal_bridge_width 0.5)
				(island_removal_mode 0)
			)
			(polygon
				(pts
					(xy 415.0995 -115.189) (xy 415.0995 -114.681) (xy 415.4805 -114.681) (xy 415.4805 -115.189)
				)
			)
		)
		(zone
			(layer "F.Cu")
			(hatch none 0.5)
			(connect_pads
				(clearance 0)
			)
			(min_thickness 0.25)
			(keepout
				(tracks allowed)
				(vias not_allowed)
				(pads allowed)
				(copperpour not_allowed)
				(footprints allowed)
			)
			(placement
				(enabled no)
				(sheetname "")
			)
			(fill
				(thermal_gap 0.5)
				(thermal_bridge_width 0.5)
				(island_removal_mode 0)
			)
			(polygon
				(pts
					(xy 415.4805 -115.189) (xy 415.4805 -114.681) (xy 415.0995 -114.681) (xy 415.0995 -115.189)
				)
			)
		)
	)
	(footprint ""
		(layer "F.Cu")
		(at 461.137 -1.524 90)
		(property "Reference" "R8B24"
			(at -0.8382 -0.67818 90)
			(unlocked yes)
			(layer "F.SilkS")
			(effects
				(font
					(size 0.4064 0.254)
					(thickness 0.1524)
				)
				(justify left)
			)
		)
		(property "Value" ""
			(at 0 0 90)
			(layer "F.Fab")
			(effects
				(font
					(size 1.27 1.27)
				)
			)
		)
		(duplicate_pad_numbers_are_jumpers no)
		(fp_poly
			(pts
				(xy -0.2794 -0.1016) (xy 0.2794 -0.1016) (xy 0.2794 0.9906) (xy -0.2794 0.9906)
			)
			(stroke
				(width 0)
				(type default)
			)
			(fill no)
			(layer "F.CrtYd")
		)
		(fp_line
			(start 0.2794 -0.1016)
			(end -0.2794 -0.1016)
			(stroke
				(width 0.1)
				(type default)
			)
			(layer "F.Fab")
		)
		(fp_line
			(start -0.2794 -0.1016)
			(end -0.2794 0.9906)
			(stroke
				(width 0.1)
				(type default)
			)
			(layer "F.Fab")
		)
		(fp_line
			(start 0.2794 0.9906)
			(end 0.2794 -0.1016)
			(stroke
				(width 0.1)
				(type default)
			)
			(layer "F.Fab")
		)
		(fp_line
			(start -0.2794 0.9906)
			(end 0.2794 0.9906)
			(stroke
				(width 0.1)
				(type default)
			)
			(layer "F.Fab")
		)
		(pad "1" smd rect
			(at 0 0 90)
			(size 0.508 0.508)
			(layers "F.Cu" "F.Mask" "F.Paste")
			(net "P3V3_STBY")
		)
		(pad "2" smd rect
			(at 0 0.889 90)
			(size 0.508 0.508)
			(layers "F.Cu" "F.Mask" "F.Paste")
			(net "SMB_HOST_STBY_LVC3_SDA_R5")
		)
		(zone
			(layer "F.Cu")
			(hatch none 0.5)
			(connect_pads
				(clearance 0)
			)
			(min_thickness 0.25)
			(keepout
				(tracks allowed)
				(vias not_allowed)
				(pads allowed)
				(copperpour not_allowed)
				(footprints allowed)
			)
			(placement
				(enabled no)
				(sheetname "")
			)
			(fill
				(thermal_gap 0.5)
				(thermal_bridge_width 0.5)
				(island_removal_mode 0)
			)
			(polygon
				(pts
					(xy 461.391 -1.27) (xy 461.391 -1.778) (xy 461.772 -1.778) (xy 461.772 -1.27)
				)
			)
		)
		(zone
			(layer "F.Cu")
			(hatch none 0.5)
			(connect_pads
				(clearance 0)
			)
			(min_thickness 0.25)
			(keepout
				(tracks not_allowed)
				(vias allowed)
				(pads allowed)
				(copperpour not_allowed)
				(footprints allowed)
			)
			(placement
				(enabled no)
				(sheetname "")
			)
			(fill
				(thermal_gap 0.5)
				(thermal_bridge_width 0.5)
				(island_removal_mode 0)
			)
			(polygon
				(pts
					(xy 461.772 -1.27) (xy 461.772 -1.778) (xy 461.391 -1.778) (xy 461.391 -1.27)
				)
			)
		)
	)
	(footprint ""
		(layer "F.Cu")
		(at 412.4325 -109.728 90)
		(property "Reference" "R8E22"
			(at 0 0 90)
			(layer "F.SilkS")
			(hide yes)
			(effects
				(font
					(size 1.27 1.27)
				)
			)
		)
		(property "Value" ""
			(at 0 0 90)
			(layer "F.Fab")
			(effects
				(font
					(size 1.27 1.27)
				)
			)
		)
		(duplicate_pad_numbers_are_jumpers no)
		(fp_poly
			(pts
				(xy -0.2794 -0.1016) (xy 0.2794 -0.1016) (xy 0.2794 0.9906) (xy -0.2794 0.9906)
			)
			(stroke
				(width 0)
				(type default)
			)
			(fill no)
			(layer "F.CrtYd")
		)
		(fp_line
			(start 0.2794 -0.1016)
			(end -0.2794 -0.1016)
			(stroke
				(width 0.1)
				(type default)
			)
			(layer "F.Fab")
		)
		(fp_line
			(start -0.2794 -0.1016)
			(end -0.2794 0.9906)
			(stroke
				(width 0.1)
				(type default)
			)
			(layer "F.Fab")
		)
		(fp_line
			(start 0.2794 0.9906)
			(end 0.2794 -0.1016)
			(stroke
				(width 0.1)
				(type default)
			)
			(layer "F.Fab")
		)
		(fp_line
			(start -0.2794 0.9906)
			(end 0.2794 0.9906)
			(stroke
				(width 0.1)
				(type default)
			)
			(layer "F.Fab")
		)
		(pad "1" smd rect
			(at 0 0 90)
			(size 0.508 0.508)
			(layers "F.Cu" "F.Mask" "F.Paste")
			(net "P3V3_STBY")
		)
		(pad "2" smd rect
			(at 0 0.889 90)
			(size 0.508 0.508)
			(layers "F.Cu" "F.Mask" "F.Paste")
			(net "IRQ_BMC_PCH_NMI_STBY_N")
		)
		(zone
			(layer "F.Cu")
			(hatch none 0.5)
			(connect_pads
				(clearance 0)
			)
			(min_thickness 0.25)
			(keepout
				(tracks allowed)
				(vias not_allowed)
				(pads allowed)
				(copperpour not_allowed)
				(footprints allowed)
			)
			(placement
				(enabled no)
				(sheetname "")
			)
			(fill
				(thermal_gap 0.5)
				(thermal_bridge_width 0.5)
				(island_removal_mode 0)
			)
			(polygon
				(pts
					(xy 412.6865 -109.474) (xy 412.6865 -109.982) (xy 413.0675 -109.982) (xy 413.0675 -109.474)
				)
			)
		)
		(zone
			(layer "F.Cu")
			(hatch none 0.5)
			(connect_pads
				(clearance 0)
			)
			(min_thickness 0.25)
			(keepout
				(tracks not_allowed)
				(vias allowed)
				(pads allowed)
				(copperpour not_allowed)
				(footprints allowed)
			)
			(placement
				(enabled no)
				(sheetname "")
			)
			(fill
				(thermal_gap 0.5)
				(thermal_bridge_width 0.5)
				(island_removal_mode 0)
			)
			(polygon
				(pts
					(xy 413.0675 -109.474) (xy 413.0675 -109.982) (xy 412.6865 -109.982) (xy 412.6865 -109.474)
				)
			)
		)
	)
	(footprint ""
		(layer "F.Cu")
		(at 269.358872 -73.279)
		(property "Reference" "C5D51"
			(at 0 0 0)
			(layer "F.SilkS")
			(hide yes)
			(effects
				(font
					(size 1.27 1.27)
				)
			)
		)
		(property "Value" ""
			(at 0 0 0)
			(layer "F.Fab")
			(effects
				(font
					(size 1.27 1.27)
				)
			)
		)
		(duplicate_pad_numbers_are_jumpers no)
		(fp_poly
			(pts
				(xy -0.4953 -0.2032) (xy 0.4953 -0.2032) (xy 0.4953 1.6002) (xy -0.4953 1.6002)
			)
			(stroke
				(width 0)
				(type default)
			)
			(fill no)
			(layer "F.CrtYd")
		)
		(fp_line
			(start -0.4953 -0.2032)
			(end 0.4953 -0.2032)
			(stroke
				(width 0.1)
				(type default)
			)
			(layer "F.Fab")
		)
		(fp_line
			(start -0.4953 1.6002)
			(end -0.4953 -0.2032)
			(stroke
				(width 0.1)
				(type default)
			)
			(layer "F.Fab")
		)
		(fp_line
			(start 0.4953 -0.2032)
			(end 0.4953 1.6002)
			(stroke
				(width 0.1)
				(type default)
			)
			(layer "F.Fab")
		)
		(fp_line
			(start 0.4953 1.6002)
			(end -0.4953 1.6002)
			(stroke
				(width 0.1)
				(type default)
			)
			(layer "F.Fab")
		)
		(pad "1" smd rect
			(at 0 0)
			(size 0.762 0.889)
			(layers "F.Cu" "F.Mask" "F.Paste")
			(net "PVCCMCP_CPU0")
		)
		(pad "2" smd rect
			(at 0 1.397)
			(size 0.762 0.889)
			(layers "F.Cu" "F.Mask" "F.Paste")
			(net "GND")
		)
		(zone
			(layer "F.Cu")
			(hatch none 0.5)
			(connect_pads
				(clearance 0)
			)
			(min_thickness 0.25)
			(keepout
				(tracks not_allowed)
				(vias allowed)
				(pads allowed)
				(copperpour not_allowed)
				(footprints allowed)
			)
			(placement
				(enabled no)
				(sheetname "")
			)
			(fill
				(thermal_gap 0.5)
				(thermal_bridge_width 0.5)
				(island_removal_mode 0)
			)
			(polygon
				(pts
					(xy 268.977872 -72.8345) (xy 269.739872 -72.8345) (xy 269.739872 -72.3265) (xy 268.977872 -72.3265)
				)
			)
		)
	)
	(footprint ""
		(layer "F.Cu")
		(at 401.066 -45.4025 180)
		(property "Reference" "R7F3"
			(at 0 0 180)
			(layer "F.SilkS")
			(hide yes)
			(effects
				(font
					(size 1.27 1.27)
				)
			)
		)
		(property "Value" ""
			(at 0 0 180)
			(layer "F.Fab")
			(effects
				(font
					(size 1.27 1.27)
				)
			)
		)
		(duplicate_pad_numbers_are_jumpers no)
		(fp_poly
			(pts
				(xy -0.2794 -0.1016) (xy 0.2794 -0.1016) (xy 0.2794 0.9906) (xy -0.2794 0.9906)
			)
			(stroke
				(width 0)
				(type default)
			)
			(fill no)
			(layer "F.CrtYd")
		)
		(fp_line
			(start 0.2794 0.9906)
			(end 0.2794 -0.1016)
			(stroke
				(width 0.1)
				(type default)
			)
			(layer "F.Fab")
		)
		(fp_line
			(start 0.2794 -0.1016)
			(end -0.2794 -0.1016)
			(stroke
				(width 0.1)
				(type default)
			)
			(layer "F.Fab")
		)
		(fp_line
			(start -0.2794 0.9906)
			(end 0.2794 0.9906)
			(stroke
				(width 0.1)
				(type default)
			)
			(layer "F.Fab")
		)
		(fp_line
			(start -0.2794 -0.1016)
			(end -0.2794 0.9906)
			(stroke
				(width 0.1)
				(type default)
			)
			(layer "F.Fab")
		)
		(pad "1" smd rect
			(at 0 0 180)
			(size 0.508 0.508)
			(layers "F.Cu" "F.Mask" "F.Paste")
			(net "SPI_BIOS_SOCKET_IO3")
		)
		(pad "2" smd rect
			(at 0 0.889 180)
			(size 0.508 0.508)
			(layers "F.Cu" "F.Mask" "F.Paste")
			(net "PU_BIOS_SPI_HOLD0_N")
		)
		(zone
			(layer "F.Cu")
			(hatch none 0.5)
			(connect_pads
				(clearance 0)
			)
			(min_thickness 0.25)
			(keepout
				(tracks not_allowed)
				(vias allowed)
				(pads allowed)
				(copperpour not_allowed)
				(footprints allowed)
			)
			(placement
				(enabled no)
				(sheetname "")
			)
			(fill
				(thermal_gap 0.5)
				(thermal_bridge_width 0.5)
				(island_removal_mode 0)
			)
			(polygon
				(pts
					(xy 401.32 -46.0375) (xy 400.812 -46.0375) (xy 400.812 -45.6565) (xy 401.32 -45.6565)
				)
			)
		)
		(zone
			(layer "F.Cu")
			(hatch none 0.5)
			(connect_pads
				(clearance 0)
			)
			(min_thickness 0.25)
			(keepout
				(tracks allowed)
				(vias not_allowed)
				(pads allowed)
				(copperpour not_allowed)
				(footprints allowed)
			)
			(placement
				(enabled no)
				(sheetname "")
			)
			(fill
				(thermal_gap 0.5)
				(thermal_bridge_width 0.5)
				(island_removal_mode 0)
			)
			(polygon
				(pts
					(xy 401.32 -45.6565) (xy 400.812 -45.6565) (xy 400.812 -46.0375) (xy 401.32 -46.0375)
				)
			)
		)
	)
	(footprint ""
		(layer "F.Cu")
		(at 346.6338 -23.4823)
		(property "Reference" "C7F11"
			(at 0 0 0)
			(layer "F.SilkS")
			(hide yes)
			(effects
				(font
					(size 1.27 1.27)
				)
			)
		)
		(property "Value" ""
			(at 0 0 0)
			(layer "F.Fab")
			(effects
				(font
					(size 1.27 1.27)
				)
			)
		)
		(duplicate_pad_numbers_are_jumpers no)
		(fp_rect
			(start -0.3048 0.9906)
			(end 0.3048 -0.1016)
			(stroke
				(width 0)
				(type default)
			)
			(fill no)
			(layer "F.CrtYd")
		)
		(fp_line
			(start -0.3048 -0.1016)
			(end -0.3048 0.9906)
			(stroke
				(width 0.1)
				(type default)
			)
			(layer "F.Fab")
		)
		(fp_line
			(start -0.3048 0.9906)
			(end 0.3048 0.9906)
			(stroke
				(width 0.1)
				(type default)
			)
			(layer "F.Fab")
		)
		(fp_line
			(start 0.3048 -0.1016)
			(end -0.3048 -0.1016)
			(stroke
				(width 0.1)
				(type default)
			)
			(layer "F.Fab")
		)
		(fp_line
			(start 0.3048 0.9906)
			(end 0.3048 -0.1016)
			(stroke
				(width 0.1)
				(type default)
			)
			(layer "F.Fab")
		)
		(pad "1" smd rect
			(at 0 0)
			(size 0.508 0.508)
			(layers "F.Cu" "F.Mask" "F.Paste")
			(net "PWRGD_PVPP_ABC_R")
		)
		(pad "2" smd rect
			(at 0 0.889)
			(size 0.508 0.508)
			(layers "F.Cu" "F.Mask" "F.Paste")
			(net "GND")
		)
		(zone
			(layer "F.Cu")
			(hatch none 0.5)
			(connect_pads
				(clearance 0)
			)
			(min_thickness 0.25)
			(keepout
				(tracks allowed)
				(vias not_allowed)
				(pads allowed)
				(copperpour not_allowed)
				(footprints allowed)
			)
			(placement
				(enabled no)
				(sheetname "")
			)
			(fill
				(thermal_gap 0.5)
				(thermal_bridge_width 0.5)
				(island_removal_mode 0)
			)
			(polygon
				(pts
					(xy 346.3798 -22.8473) (xy 346.8878 -22.8473) (xy 346.8878 -23.2283) (xy 346.3798 -23.2283)
				)
			)
		)
		(zone
			(layer "F.Cu")
			(hatch none 0.5)
			(connect_pads
				(clearance 0)
			)
			(min_thickness 0.25)
			(keepout
				(tracks not_allowed)
				(vias allowed)
				(pads allowed)
				(copperpour not_allowed)
				(footprints allowed)
			)
			(placement
				(enabled no)
				(sheetname "")
			)
			(fill
				(thermal_gap 0.5)
				(thermal_bridge_width 0.5)
				(island_removal_mode 0)
			)
			(polygon
				(pts
					(xy 346.3798 -22.8473) (xy 346.8878 -22.8473) (xy 346.8878 -23.2283) (xy 346.3798 -23.2283)
				)
			)
		)
	)
	(footprint ""
		(layer "F.Cu")
		(at 112.182402 -77.382116)
		(property "Reference" "C3D14"
			(at 0 0 0)
			(layer "F.SilkS")
			(hide yes)
			(effects
				(font
					(size 1.27 1.27)
				)
			)
		)
		(property "Value" ""
			(at 0 0 0)
			(layer "F.Fab")
			(effects
				(font
					(size 1.27 1.27)
				)
			)
		)
		(duplicate_pad_numbers_are_jumpers no)
		(fp_poly
			(pts
				(xy -0.4953 -0.2032) (xy 0.4953 -0.2032) (xy 0.4953 1.6002) (xy -0.4953 1.6002)
			)
			(stroke
				(width 0)
				(type default)
			)
			(fill no)
			(layer "F.CrtYd")
		)
		(fp_line
			(start -0.4953 -0.2032)
			(end 0.4953 -0.2032)
			(stroke
				(width 0.1)
				(type default)
			)
			(layer "F.Fab")
		)
		(fp_line
			(start -0.4953 1.6002)
			(end -0.4953 -0.2032)
			(stroke
				(width 0.1)
				(type default)
			)
			(layer "F.Fab")
		)
		(fp_line
			(start 0.4953 -0.2032)
			(end 0.4953 1.6002)
			(stroke
				(width 0.1)
				(type default)
			)
			(layer "F.Fab")
		)
		(fp_line
			(start 0.4953 1.6002)
			(end -0.4953 1.6002)
			(stroke
				(width 0.1)
				(type default)
			)
			(layer "F.Fab")
		)
		(pad "1" smd rect
			(at 0 0)
			(size 0.762 0.889)
			(layers "F.Cu" "F.Mask" "F.Paste")
			(net "PVCCMCP_CPU1")
		)
		(pad "2" smd rect
			(at 0 1.397)
			(size 0.762 0.889)
			(layers "F.Cu" "F.Mask" "F.Paste")
			(net "GND")
		)
		(zone
			(layer "F.Cu")
			(hatch none 0.5)
			(connect_pads
				(clearance 0)
			)
			(min_thickness 0.25)
			(keepout
				(tracks not_allowed)
				(vias allowed)
				(pads allowed)
				(copperpour not_allowed)
				(footprints allowed)
			)
			(placement
				(enabled no)
				(sheetname "")
			)
			(fill
				(thermal_gap 0.5)
				(thermal_bridge_width 0.5)
				(island_removal_mode 0)
			)
			(polygon
				(pts
					(xy 111.801402 -76.937616) (xy 112.563402 -76.937616) (xy 112.563402 -76.429616) (xy 111.801402 -76.429616)
				)
			)
		)
	)
)
